# T6G (Grand Teton) — schematic netlist excerpt (pin names and nets, part order shuffled) for the footprints in the layout excerpt that follows; sources: Cadence DE-HDL packaged netlist, KiCad conversion of 04192023_DAF0TMB3IC0_F0TG_MB_C_brd_V02_OCP.brd

C1544  Q_CAP_DIFFBUS  DIFF BUS_0.22UF 6.3V 20% X6S  pkg C0201  page 67 : \1\ = P5E_CPU1_P3_TX_C_DN<1> ; \2\ = P5E_CPU1_P3_TX_DN<1>
R3324  Q_RES  33.2 1% CHIP  pkg 0402LF  page 81 : A = GPU_FPGA_READY_ISO_R ; B = GPU_FPGA_READY_ISO
PR189  Q_RES  5.6 1% CHIP  pkg 0402LF  page 211 : A = SW_PVDDCR_CPU0_P1_BOOT1 ; B = SW_PVDDCR_CPU0_P1_BOOT1_RC

(kicad_pcb
	(version 20260206)
	(generator "pcbnew")
	(generator_version "10.0")
	(general
		(thickness 1.6)
		(legacy_teardrops no)
	)
	(paper "A4")
	(title_block
		(title "04192023_DAF0TMB3IC0_F0TG_MB_C_brd_V02_OCP.brd")
		(comment 1 "Grand Teton / footprints 4189-4191 of 8354")
	)
	(layers
		(0 "F.Cu" signal "TOP")
		(4 "In1.Cu" signal "GND")
		(6 "In2.Cu" signal "IN1")
		(8 "In3.Cu" signal "GND1")
		(10 "In4.Cu" signal "IN2")
		(12 "In5.Cu" signal "GND2")
		(14 "In6.Cu" signal "IN3")
		(16 "In7.Cu" signal "GND3")
		(18 "In8.Cu" signal "VCC")
		(20 "In9.Cu" signal "VCC1")
		(22 "In10.Cu" signal "GND4")
		(24 "In11.Cu" signal "IN4")
		(26 "In12.Cu" signal "GND5")
		(28 "In13.Cu" signal "IN5")
		(30 "In14.Cu" signal "GND6")
		(32 "In15.Cu" signal "IN6")
		(34 "In16.Cu" signal "GND7")
		(2 "B.Cu" signal "BOTTOM")
		(9 "F.Adhes" user "F.Adhesive")
		(11 "B.Adhes" user "B.Adhesive")
		(13 "F.Paste" user "Package Geometry/Pastemask Top")
		(15 "B.Paste" user "Package Geometry/Pastemask Bottom")
		(5 "F.SilkS" user "Ref Des/Silkscreen Top")
		(7 "B.SilkS" user "Ref Des/Silkscreen Bottom")
		(1 "F.Mask" user "Board Geometry/Soldermask Top")
		(3 "B.Mask" user "Board Geometry/Soldermask Bottom")
		(17 "Dwgs.User" user "User.Drawings")
		(19 "Cmts.User" user "User.Comments")
		(21 "Eco1.User" user "User.Eco1")
		(23 "Eco2.User" user "User.Eco2")
		(25 "Edge.Cuts" user "Board Geometry/Outline")
		(27 "Margin" user)
		(31 "F.CrtYd" user "Package Geometry/Place Bound Top")
		(29 "B.CrtYd" user "Package Geometry/Place Bound Bottom")
		(35 "F.Fab" user "Ref Des/Assembly Top")
		(33 "B.Fab" user "Ref Des/Assembly Bottom")
	)
	(footprint ""
		(layer "F.Cu")
		(at 201.082148 -122.798332)
		(property "Reference" "R3324"
			(at 0 0 0)
			(layer "F.SilkS")
			(hide yes)
			(effects
				(font
					(size 1.27 1.27)
				)
			)
		)
		(property "Value" ""
			(at 0 0 0)
			(layer "F.Fab")
			(effects
				(font
					(size 1.27 1.27)
				)
			)
		)
		(duplicate_pad_numbers_are_jumpers no)
		(fp_line
			(start -0.7874 -0.4064)
			(end 0.7874 -0.4064)
			(stroke
				(width 0.1524)
				(type default)
			)
			(layer "F.SilkS")
		)
		(fp_line
			(start -0.7874 0.4064)
			(end -0.7874 -0.4064)
			(stroke
				(width 0.1524)
				(type default)
			)
			(layer "F.SilkS")
		)
		(fp_line
			(start 0.7874 -0.4064)
			(end 0.7874 0.4064)
			(stroke
				(width 0.1524)
				(type default)
			)
			(layer "F.SilkS")
		)
		(fp_line
			(start 0.7874 0.4064)
			(end -0.7874 0.4064)
			(stroke
				(width 0.1524)
				(type default)
			)
			(layer "F.SilkS")
		)
		(fp_line
			(start -0.67945 -0.305054)
			(end -0.12065 -0.305054)
			(stroke
				(width 0.1)
				(type default)
			)
			(layer "F.Fab")
		)
		(fp_line
			(start -0.67945 0.3048)
			(end -0.67945 -0.305054)
			(stroke
				(width 0.1)
				(type default)
			)
			(layer "F.Fab")
		)
		(fp_line
			(start -0.12065 -0.305054)
			(end -0.12065 -0.2794)
			(stroke
				(width 0.1)
				(type default)
			)
			(layer "F.Fab")
		)
		(fp_line
			(start -0.12065 -0.2794)
			(end 0.12065 -0.2794)
			(stroke
				(width 0.1)
				(type default)
			)
			(layer "F.Fab")
		)
		(fp_line
			(start -0.12065 0.2794)
			(end -0.12065 0.3048)
			(stroke
				(width 0.1)
				(type default)
			)
			(layer "F.Fab")
		)
		(fp_line
			(start -0.12065 0.3048)
			(end -0.67945 0.3048)
			(stroke
				(width 0.1)
				(type default)
			)
			(layer "F.Fab")
		)
		(fp_line
			(start 0.120396 0.2794)
			(end -0.12065 0.2794)
			(stroke
				(width 0.1)
				(type default)
			)
			(layer "F.Fab")
		)
		(fp_line
			(start 0.120396 0.3048)
			(end 0.120396 0.2794)
			(stroke
				(width 0.1)
				(type default)
			)
			(layer "F.Fab")
		)
		(fp_line
			(start 0.12065 -0.3048)
			(end 0.67945 -0.3048)
			(stroke
				(width 0.1)
				(type default)
			)
			(layer "F.Fab")
		)
		(fp_line
			(start 0.12065 -0.2794)
			(end 0.12065 -0.3048)
			(stroke
				(width 0.1)
				(type default)
			)
			(layer "F.Fab")
		)
		(fp_line
			(start 0.67945 -0.3048)
			(end 0.67945 0.3048)
			(stroke
				(width 0.1)
				(type default)
			)
			(layer "F.Fab")
		)
		(fp_line
			(start 0.67945 0.3048)
			(end 0.120396 0.3048)
			(stroke
				(width 0.1)
				(type default)
			)
			(layer "F.Fab")
		)
		(pad "1" smd circle
			(at -0.40005 0)
			(size 0 0)
			(layers "F.Cu" "F.Mask" "F.Paste")
			(net "GPU_FPGA_READY_ISO_R")
		)
		(pad "2" smd circle
			(at 0.40005 0)
			(size 0 0)
			(layers "F.Cu" "F.Mask" "F.Paste")
			(net "GPU_FPGA_READY_ISO")
		)
	)
	(footprint ""
		(layer "F.Cu")
		(at 81.525364 -178.0921 -90)
		(property "Reference" "PR189"
			(at 0 0 270)
			(layer "F.SilkS")
			(hide yes)
			(effects
				(font
					(size 1.27 1.27)
				)
			)
		)
		(property "Value" ""
			(at 0 0 270)
			(layer "F.Fab")
			(effects
				(font
					(size 1.27 1.27)
				)
			)
		)
		(duplicate_pad_numbers_are_jumpers no)
		(fp_line
			(start -0.7874 0.4064)
			(end -0.7874 -0.4064)
			(stroke
				(width 0.1524)
				(type default)
			)
			(layer "F.SilkS")
		)
		(fp_line
			(start 0.7874 0.4064)
			(end -0.7874 0.4064)
			(stroke
				(width 0.1524)
				(type default)
			)
			(layer "F.SilkS")
		)
		(fp_line
			(start -0.7874 -0.4064)
			(end 0.7874 -0.4064)
			(stroke
				(width 0.1524)
				(type default)
			)
			(layer "F.SilkS")
		)
		(fp_line
			(start 0.7874 -0.4064)
			(end 0.7874 0.4064)
			(stroke
				(width 0.1524)
				(type default)
			)
			(layer "F.SilkS")
		)
		(fp_line
			(start -0.67945 0.3048)
			(end -0.67945 -0.305054)
			(stroke
				(width 0.1)
				(type default)
			)
			(layer "F.Fab")
		)
		(fp_line
			(start -0.12065 0.3048)
			(end -0.67945 0.3048)
			(stroke
				(width 0.1)
				(type default)
			)
			(layer "F.Fab")
		)
		(fp_line
			(start 0.120396 0.3048)
			(end 0.120396 0.2794)
			(stroke
				(width 0.1)
				(type default)
			)
			(layer "F.Fab")
		)
		(fp_line
			(start 0.67945 0.3048)
			(end 0.120396 0.3048)
			(stroke
				(width 0.1)
				(type default)
			)
			(layer "F.Fab")
		)
		(fp_line
			(start -0.12065 0.2794)
			(end -0.12065 0.3048)
			(stroke
				(width 0.1)
				(type default)
			)
			(layer "F.Fab")
		)
		(fp_line
			(start 0.120396 0.2794)
			(end -0.12065 0.2794)
			(stroke
				(width 0.1)
				(type default)
			)
			(layer "F.Fab")
		)
		(fp_line
			(start -0.12065 -0.2794)
			(end 0.12065 -0.2794)
			(stroke
				(width 0.1)
				(type default)
			)
			(layer "F.Fab")
		)
		(fp_line
			(start 0.12065 -0.2794)
			(end 0.12065 -0.3048)
			(stroke
				(width 0.1)
				(type default)
			)
			(layer "F.Fab")
		)
		(fp_line
			(start 0.12065 -0.3048)
			(end 0.67945 -0.3048)
			(stroke
				(width 0.1)
				(type default)
			)
			(layer "F.Fab")
		)
		(fp_line
			(start 0.67945 -0.3048)
			(end 0.67945 0.3048)
			(stroke
				(width 0.1)
				(type default)
			)
			(layer "F.Fab")
		)
		(fp_line
			(start -0.67945 -0.305054)
			(end -0.12065 -0.305054)
			(stroke
				(width 0.1)
				(type default)
			)
			(layer "F.Fab")
		)
		(fp_line
			(start -0.12065 -0.305054)
			(end -0.12065 -0.2794)
			(stroke
				(width 0.1)
				(type default)
			)
			(layer "F.Fab")
		)
		(pad "1" smd circle
			(at -0.40005 0 270)
			(size 0 0)
			(layers "F.Cu" "F.Mask" "F.Paste")
			(net "SW_PVDDCR_CPU0_P1_BOOT1")
		)
		(pad "2" smd circle
			(at 0.40005 0 270)
			(size 0 0)
			(layers "F.Cu" "F.Mask" "F.Paste")
			(net "SW_PVDDCR_CPU0_P1_BOOT1_RC")
		)
	)
	(footprint ""
		(layer "F.Cu")
		(at 110.067344 -376.85726 180)
		(property "Reference" "C1544"
			(at 0 0 180)
			(layer "F.SilkS")
			(hide yes)
			(effects
				(font
					(size 1.27 1.27)
				)
			)
		)
		(property "Value" ""
			(at 0 0 180)
			(layer "F.Fab")
			(effects
				(font
					(size 1.27 1.27)
				)
			)
		)
		(duplicate_pad_numbers_are_jumpers no)
		(fp_line
			(start 0.299974 0.150114)
			(end -0.299974 0.150114)
			(stroke
				(width 0.1)
				(type default)
			)
			(layer "F.Fab")
		)
		(fp_line
			(start 0.299974 -0.150114)
			(end 0.299974 0.150114)
			(stroke
				(width 0.1)
				(type default)
			)
			(layer "F.Fab")
		)
		(fp_line
			(start -0.299974 0.150114)
			(end -0.299974 -0.150114)
			(stroke
				(width 0.1)
				(type default)
			)
			(layer "F.Fab")
		)
		(fp_line
			(start -0.299974 -0.150114)
			(end 0.299974 -0.150114)
			(stroke
				(width 0.1)
				(type default)
			)
			(layer "F.Fab")
		)
		(pad "1" smd rect
			(at -0.2667 0 180)
			(size 0.3048 0.381)
			(layers "F.Cu" "F.Mask" "F.Paste")
			(net "P5E_CPU1_P3_TX_C_DN<1>")
		)
		(pad "2" smd rect
			(at 0.2667 0 180)
			(size 0.3048 0.381)
			(layers "F.Cu" "F.Mask" "F.Paste")
			(net "P5E_CPU1_P3_TX_DN<1>")
		)
	)
)
